# T6G (Grand Teton) — schematic netlist excerpt (pin names and nets, part order shuffled) for the footprints in the layout excerpt that follows; sources: Cadence DE-HDL packaged netlist, KiCad conversion of 04192023_DAF0TMB3IC0_F0TG_MB_C_brd_V02_OCP.brd

R3029  Q_RES  4.7K 5% CHIP  pkg 0402LF  page 127 : A = P3V3_AUX ; B = FM_SMB_1_ALERT_GPU
R8123  Q_RES  1M 1% CHIP  pkg 0402LF  page 268 : A = P12V_AUX_UV_TRIGGER ; B = IRQ_UV_DETECT_R2_N

(kicad_pcb
	(version 20260206)
	(generator "pcbnew")
	(generator_version "10.0")
	(general
		(thickness 1.6)
		(legacy_teardrops no)
	)
	(paper "A4")
	(title_block
		(title "04192023_DAF0TMB3IC0_F0TG_MB_C_brd_V02_OCP.brd")
		(comment 1 "Grand Teton / footprints 4878-4879 of 8354")
	)
	(layers
		(0 "F.Cu" signal "TOP")
		(4 "In1.Cu" signal "GND")
		(6 "In2.Cu" signal "IN1")
		(8 "In3.Cu" signal "GND1")
		(10 "In4.Cu" signal "IN2")
		(12 "In5.Cu" signal "GND2")
		(14 "In6.Cu" signal "IN3")
		(16 "In7.Cu" signal "GND3")
		(18 "In8.Cu" signal "VCC")
		(20 "In9.Cu" signal "VCC1")
		(22 "In10.Cu" signal "GND4")
		(24 "In11.Cu" signal "IN4")
		(26 "In12.Cu" signal "GND5")
		(28 "In13.Cu" signal "IN5")
		(30 "In14.Cu" signal "GND6")
		(32 "In15.Cu" signal "IN6")
		(34 "In16.Cu" signal "GND7")
		(2 "B.Cu" signal "BOTTOM")
		(9 "F.Adhes" user "F.Adhesive")
		(11 "B.Adhes" user "B.Adhesive")
		(13 "F.Paste" user "Package Geometry/Pastemask Top")
		(15 "B.Paste" user "Package Geometry/Pastemask Bottom")
		(5 "F.SilkS" user "Ref Des/Silkscreen Top")
		(7 "B.SilkS" user "Ref Des/Silkscreen Bottom")
		(1 "F.Mask" user "Board Geometry/Soldermask Top")
		(3 "B.Mask" user "Board Geometry/Soldermask Bottom")
		(17 "Dwgs.User" user "User.Drawings")
		(19 "Cmts.User" user "User.Comments")
		(21 "Eco1.User" user "User.Eco1")
		(23 "Eco2.User" user "User.Eco2")
		(25 "Edge.Cuts" user "Board Geometry/Outline")
		(27 "Margin" user)
		(31 "F.CrtYd" user "Package Geometry/Place Bound Top")
		(29 "B.CrtYd" user "Package Geometry/Place Bound Bottom")
		(35 "F.Fab" user "Ref Des/Assembly Top")
		(33 "B.Fab" user "Ref Des/Assembly Bottom")
	)
	(footprint ""
		(layer "F.Cu")
		(at 112.672876 -418.090858 -90)
		(property "Reference" "R3029"
			(at 0 0 270)
			(layer "F.SilkS")
			(hide yes)
			(effects
				(font
					(size 1.27 1.27)
				)
			)
		)
		(property "Value" ""
			(at 0 0 270)
			(layer "F.Fab")
			(effects
				(font
					(size 1.27 1.27)
				)
			)
		)
		(duplicate_pad_numbers_are_jumpers no)
		(fp_line
			(start -0.7874 0.4064)
			(end -0.7874 -0.4064)
			(stroke
				(width 0.1524)
				(type default)
			)
			(layer "F.SilkS")
		)
		(fp_line
			(start 0.7874 0.4064)
			(end -0.7874 0.4064)
			(stroke
				(width 0.1524)
				(type default)
			)
			(layer "F.SilkS")
		)
		(fp_line
			(start -0.7874 -0.4064)
			(end 0.7874 -0.4064)
			(stroke
				(width 0.1524)
				(type default)
			)
			(layer "F.SilkS")
		)
		(fp_line
			(start 0.7874 -0.4064)
			(end 0.7874 0.4064)
			(stroke
				(width 0.1524)
				(type default)
			)
			(layer "F.SilkS")
		)
		(fp_line
			(start -0.67945 0.3048)
			(end -0.67945 -0.305054)
			(stroke
				(width 0.1)
				(type default)
			)
			(layer "F.Fab")
		)
		(fp_line
			(start -0.12065 0.3048)
			(end -0.67945 0.3048)
			(stroke
				(width 0.1)
				(type default)
			)
			(layer "F.Fab")
		)
		(fp_line
			(start 0.120396 0.3048)
			(end 0.120396 0.2794)
			(stroke
				(width 0.1)
				(type default)
			)
			(layer "F.Fab")
		)
		(fp_line
			(start 0.67945 0.3048)
			(end 0.120396 0.3048)
			(stroke
				(width 0.1)
				(type default)
			)
			(layer "F.Fab")
		)
		(fp_line
			(start -0.12065 0.2794)
			(end -0.12065 0.3048)
			(stroke
				(width 0.1)
				(type default)
			)
			(layer "F.Fab")
		)
		(fp_line
			(start 0.120396 0.2794)
			(end -0.12065 0.2794)
			(stroke
				(width 0.1)
				(type default)
			)
			(layer "F.Fab")
		)
		(fp_line
			(start -0.12065 -0.2794)
			(end 0.12065 -0.2794)
			(stroke
				(width 0.1)
				(type default)
			)
			(layer "F.Fab")
		)
		(fp_line
			(start 0.12065 -0.2794)
			(end 0.12065 -0.3048)
			(stroke
				(width 0.1)
				(type default)
			)
			(layer "F.Fab")
		)
		(fp_line
			(start 0.12065 -0.3048)
			(end 0.67945 -0.3048)
			(stroke
				(width 0.1)
				(type default)
			)
			(layer "F.Fab")
		)
		(fp_line
			(start 0.67945 -0.3048)
			(end 0.67945 0.3048)
			(stroke
				(width 0.1)
				(type default)
			)
			(layer "F.Fab")
		)
		(fp_line
			(start -0.67945 -0.305054)
			(end -0.12065 -0.305054)
			(stroke
				(width 0.1)
				(type default)
			)
			(layer "F.Fab")
		)
		(fp_line
			(start -0.12065 -0.305054)
			(end -0.12065 -0.2794)
			(stroke
				(width 0.1)
				(type default)
			)
			(layer "F.Fab")
		)
		(pad "1" smd circle
			(at -0.40005 0 270)
			(size 0 0)
			(layers "F.Cu" "F.Mask" "F.Paste")
			(net "P3V3_AUX")
		)
		(pad "2" smd circle
			(at 0.40005 0 270)
			(size 0 0)
			(layers "F.Cu" "F.Mask" "F.Paste")
			(net "FM_SMB_1_ALERT_GPU")
		)
	)
	(footprint ""
		(layer "F.Cu")
		(at 142.367 -120.269 180)
		(property "Reference" "R8123"
			(at 0 0 180)
			(layer "F.SilkS")
			(hide yes)
			(effects
				(font
					(size 1.27 1.27)
				)
			)
		)
		(property "Value" ""
			(at 0 0 180)
			(layer "F.Fab")
			(effects
				(font
					(size 1.27 1.27)
				)
			)
		)
		(duplicate_pad_numbers_are_jumpers no)
		(fp_line
			(start 0.7874 0.4064)
			(end -0.7874 0.4064)
			(stroke
				(width 0.1524)
				(type default)
			)
			(layer "F.SilkS")
		)
		(fp_line
			(start 0.7874 -0.4064)
			(end 0.7874 0.4064)
			(stroke
				(width 0.1524)
				(type default)
			)
			(layer "F.SilkS")
		)
		(fp_line
			(start -0.7874 0.4064)
			(end -0.7874 -0.4064)
			(stroke
				(width 0.1524)
				(type default)
			)
			(layer "F.SilkS")
		)
		(fp_line
			(start -0.7874 -0.4064)
			(end 0.7874 -0.4064)
			(stroke
				(width 0.1524)
				(type default)
			)
			(layer "F.SilkS")
		)
		(fp_line
			(start 0.67945 0.3048)
			(end 0.120396 0.3048)
			(stroke
				(width 0.1)
				(type default)
			)
			(layer "F.Fab")
		)
		(fp_line
			(start 0.67945 -0.3048)
			(end 0.67945 0.3048)
			(stroke
				(width 0.1)
				(type default)
			)
			(layer "F.Fab")
		)
		(fp_line
			(start 0.12065 -0.2794)
			(end 0.12065 -0.3048)
			(stroke
				(width 0.1)
				(type default)
			)
			(layer "F.Fab")
		)
		(fp_line
			(start 0.12065 -0.3048)
			(end 0.67945 -0.3048)
			(stroke
				(width 0.1)
				(type default)
			)
			(layer "F.Fab")
		)
		(fp_line
			(start 0.120396 0.3048)
			(end 0.120396 0.2794)
			(stroke
				(width 0.1)
				(type default)
			)
			(layer "F.Fab")
		)
		(fp_line
			(start 0.120396 0.2794)
			(end -0.12065 0.2794)
			(stroke
				(width 0.1)
				(type default)
			)
			(layer "F.Fab")
		)
		(fp_line
			(start -0.12065 0.3048)
			(end -0.67945 0.3048)
			(stroke
				(width 0.1)
				(type default)
			)
			(layer "F.Fab")
		)
		(fp_line
			(start -0.12065 0.2794)
			(end -0.12065 0.3048)
			(stroke
				(width 0.1)
				(type default)
			)
			(layer "F.Fab")
		)
		(fp_line
			(start -0.12065 -0.2794)
			(end 0.12065 -0.2794)
			(stroke
				(width 0.1)
				(type default)
			)
			(layer "F.Fab")
		)
		(fp_line
			(start -0.12065 -0.305054)
			(end -0.12065 -0.2794)
			(stroke
				(width 0.1)
				(type default)
			)
			(layer "F.Fab")
		)
		(fp_line
			(start -0.67945 0.3048)
			(end -0.67945 -0.305054)
			(stroke
				(width 0.1)
				(type default)
			)
			(layer "F.Fab")
		)
		(fp_line
			(start -0.67945 -0.305054)
			(end -0.12065 -0.305054)
			(stroke
				(width 0.1)
				(type default)
			)
			(layer "F.Fab")
		)
		(pad "1" smd circle
			(at -0.40005 0 180)
			(size 0 0)
			(layers "F.Cu" "F.Mask" "F.Paste")
			(net "P12V_AUX_UV_TRIGGER")
		)
		(pad "2" smd circle
			(at 0.40005 0 180)
			(size 0 0)
			(layers "F.Cu" "F.Mask" "F.Paste")
			(net "IRQ_UV_DETECT_R2_N")
		)
	)
)
